# SCM (Grand Teton) — schematic netlist excerpt (pin names and nets, part order shuffled) for the footprints in the layout excerpt that follows; sources: Cadence DE-HDL packaged netlist, KiCad conversion of 12092022_DA0F0TMDCD0_F0T_Management_Board_D_brd_V3_OCP.brd

R280  Q_RES  0 5% EMPTY  pkg 0402LF  page 17 : A = P1V2_AUX ; B = P1V2_P1V0_I3C_VDDL2
R899  Q_RES  0 5% CHIP  pkg 0402LF  page 36 : A = FM_UARTSW_MSB_R_N ; B = FM_UARTSW_MSB_N

(kicad_pcb
	(version 20260206)
	(generator "pcbnew")
	(generator_version "10.0")
	(general
		(thickness 1.6)
		(legacy_teardrops no)
	)
	(paper "A4")
	(title_block
		(title "12092022_DA0F0TMDCD0_F0T_Management_Board_D_brd_V3_OCP.brd")
		(comment 1 "Grand Teton / footprints 733-734 of 1440")
	)
	(layers
		(0 "F.Cu" signal "TOP")
		(4 "In1.Cu" signal "GND")
		(6 "In2.Cu" signal "IN1")
		(8 "In3.Cu" signal "GND1")
		(10 "In4.Cu" signal "IN2")
		(12 "In5.Cu" signal "VCC")
		(14 "In6.Cu" signal "VCC1")
		(16 "In7.Cu" signal "IN3")
		(18 "In8.Cu" signal "GND2")
		(20 "In9.Cu" signal "IN4")
		(22 "In10.Cu" signal "GND3")
		(2 "B.Cu" signal "BOTTOM")
		(9 "F.Adhes" user "F.Adhesive")
		(11 "B.Adhes" user "B.Adhesive")
		(13 "F.Paste" user "Package Geometry/Pastemask Top")
		(15 "B.Paste" user "Package Geometry/Pastemask Bottom")
		(5 "F.SilkS" user "Ref Des/Silkscreen Top")
		(7 "B.SilkS" user "Ref Des/Silkscreen Bottom")
		(1 "F.Mask" user "Board Geometry/Soldermask Top")
		(3 "B.Mask" user "Board Geometry/Soldermask Bottom")
		(17 "Dwgs.User" user "User.Drawings")
		(19 "Cmts.User" user "User.Comments")
		(21 "Eco1.User" user "User.Eco1")
		(23 "Eco2.User" user "User.Eco2")
		(25 "Edge.Cuts" user "Board Geometry/Outline")
		(27 "Margin" user)
		(31 "F.CrtYd" user "Package Geometry/Place Bound Top")
		(29 "B.CrtYd" user "Package Geometry/Place Bound Bottom")
		(35 "F.Fab" user "Ref Des/Assembly Top")
		(33 "B.Fab" user "Ref Des/Assembly Bottom")
	)
	(footprint ""
		(layer "B.Cu")
		(at 15.367 -106.426 90)
		(property "Reference" "R899"
			(at 0 0 90)
			(layer "B.SilkS")
			(hide yes)
			(effects
				(font
					(size 1.27 1.27)
				)
				(justify mirror)
			)
		)
		(property "Value" ""
			(at 0 0 90)
			(layer "B.Fab")
			(effects
				(font
					(size 1.27 1.27)
				)
				(justify mirror)
			)
		)
		(duplicate_pad_numbers_are_jumpers no)
		(fp_line
			(start 0.7874 -0.4064)
			(end -0.7874 -0.4064)
			(stroke
				(width 0.1524)
				(type default)
			)
			(layer "B.SilkS")
		)
		(fp_line
			(start -0.7874 -0.4064)
			(end -0.7874 0.4064)
			(stroke
				(width 0.1524)
				(type default)
			)
			(layer "B.SilkS")
		)
		(fp_line
			(start 0.7874 0.4064)
			(end 0.7874 -0.4064)
			(stroke
				(width 0.1524)
				(type default)
			)
			(layer "B.SilkS")
		)
		(fp_line
			(start -0.7874 0.4064)
			(end 0.7874 0.4064)
			(stroke
				(width 0.1524)
				(type default)
			)
			(layer "B.SilkS")
		)
		(fp_line
			(start 0.67945 -0.305054)
			(end 0.12065 -0.305054)
			(stroke
				(width 0.1)
				(type default)
			)
			(layer "B.Fab")
		)
		(fp_line
			(start 0.12065 -0.305054)
			(end 0.12065 -0.2794)
			(stroke
				(width 0.1)
				(type default)
			)
			(layer "B.Fab")
		)
		(fp_line
			(start -0.12065 -0.3048)
			(end -0.67945 -0.3048)
			(stroke
				(width 0.1)
				(type default)
			)
			(layer "B.Fab")
		)
		(fp_line
			(start -0.67945 -0.3048)
			(end -0.67945 0.3048)
			(stroke
				(width 0.1)
				(type default)
			)
			(layer "B.Fab")
		)
		(fp_line
			(start 0.12065 -0.2794)
			(end -0.12065 -0.2794)
			(stroke
				(width 0.1)
				(type default)
			)
			(layer "B.Fab")
		)
		(fp_line
			(start -0.12065 -0.2794)
			(end -0.12065 -0.3048)
			(stroke
				(width 0.1)
				(type default)
			)
			(layer "B.Fab")
		)
		(fp_line
			(start 0.12065 0.2794)
			(end 0.12065 0.3048)
			(stroke
				(width 0.1)
				(type default)
			)
			(layer "B.Fab")
		)
		(fp_line
			(start -0.120396 0.2794)
			(end 0.12065 0.2794)
			(stroke
				(width 0.1)
				(type default)
			)
			(layer "B.Fab")
		)
		(fp_line
			(start 0.67945 0.3048)
			(end 0.67945 -0.305054)
			(stroke
				(width 0.1)
				(type default)
			)
			(layer "B.Fab")
		)
		(fp_line
			(start 0.12065 0.3048)
			(end 0.67945 0.3048)
			(stroke
				(width 0.1)
				(type default)
			)
			(layer "B.Fab")
		)
		(fp_line
			(start -0.120396 0.3048)
			(end -0.120396 0.2794)
			(stroke
				(width 0.1)
				(type default)
			)
			(layer "B.Fab")
		)
		(fp_line
			(start -0.67945 0.3048)
			(end -0.120396 0.3048)
			(stroke
				(width 0.1)
				(type default)
			)
			(layer "B.Fab")
		)
		(pad "1" smd circle
			(at 0.40005 0 270)
			(size 0 0)
			(layers "B.Cu" "B.Mask" "B.Paste")
			(net "FM_UARTSW_MSB_R_N")
		)
		(pad "2" smd circle
			(at -0.40005 0 270)
			(size 0 0)
			(layers "B.Cu" "B.Mask" "B.Paste")
			(net "FM_UARTSW_MSB_N")
		)
	)
	(footprint ""
		(layer "B.Cu")
		(at 40.889936 -51.38547 180)
		(property "Reference" "R280"
			(at 0 0 0)
			(layer "B.SilkS")
			(hide yes)
			(effects
				(font
					(size 1.27 1.27)
				)
				(justify mirror)
			)
		)
		(property "Value" ""
			(at 0 0 0)
			(layer "B.Fab")
			(effects
				(font
					(size 1.27 1.27)
				)
				(justify mirror)
			)
		)
		(duplicate_pad_numbers_are_jumpers no)
		(fp_line
			(start 0.7874 0.4064)
			(end 0.7874 -0.4064)
			(stroke
				(width 0.1524)
				(type default)
			)
			(layer "B.SilkS")
		)
		(fp_line
			(start 0.7874 -0.4064)
			(end -0.7874 -0.4064)
			(stroke
				(width 0.1524)
				(type default)
			)
			(layer "B.SilkS")
		)
		(fp_line
			(start -0.7874 0.4064)
			(end 0.7874 0.4064)
			(stroke
				(width 0.1524)
				(type default)
			)
			(layer "B.SilkS")
		)
		(fp_line
			(start -0.7874 -0.4064)
			(end -0.7874 0.4064)
			(stroke
				(width 0.1524)
				(type default)
			)
			(layer "B.SilkS")
		)
		(fp_line
			(start 0.67945 0.3048)
			(end 0.67945 -0.305054)
			(stroke
				(width 0.1)
				(type default)
			)
			(layer "B.Fab")
		)
		(fp_line
			(start 0.67945 -0.305054)
			(end 0.12065 -0.305054)
			(stroke
				(width 0.1)
				(type default)
			)
			(layer "B.Fab")
		)
		(fp_line
			(start 0.12065 0.3048)
			(end 0.67945 0.3048)
			(stroke
				(width 0.1)
				(type default)
			)
			(layer "B.Fab")
		)
		(fp_line
			(start 0.12065 0.2794)
			(end 0.12065 0.3048)
			(stroke
				(width 0.1)
				(type default)
			)
			(layer "B.Fab")
		)
		(fp_line
			(start 0.12065 -0.2794)
			(end -0.12065 -0.2794)
			(stroke
				(width 0.1)
				(type default)
			)
			(layer "B.Fab")
		)
		(fp_line
			(start 0.12065 -0.305054)
			(end 0.12065 -0.2794)
			(stroke
				(width 0.1)
				(type default)
			)
			(layer "B.Fab")
		)
		(fp_line
			(start -0.120396 0.3048)
			(end -0.120396 0.2794)
			(stroke
				(width 0.1)
				(type default)
			)
			(layer "B.Fab")
		)
		(fp_line
			(start -0.120396 0.2794)
			(end 0.12065 0.2794)
			(stroke
				(width 0.1)
				(type default)
			)
			(layer "B.Fab")
		)
		(fp_line
			(start -0.12065 -0.2794)
			(end -0.12065 -0.3048)
			(stroke
				(width 0.1)
				(type default)
			)
			(layer "B.Fab")
		)
		(fp_line
			(start -0.12065 -0.3048)
			(end -0.67945 -0.3048)
			(stroke
				(width 0.1)
				(type default)
			)
			(layer "B.Fab")
		)
		(fp_line
			(start -0.67945 0.3048)
			(end -0.120396 0.3048)
			(stroke
				(width 0.1)
				(type default)
			)
			(layer "B.Fab")
		)
		(fp_line
			(start -0.67945 -0.3048)
			(end -0.67945 0.3048)
			(stroke
				(width 0.1)
				(type default)
			)
			(layer "B.Fab")
		)
		(pad "1" smd circle
			(at 0.40005 0)
			(size 0 0)
			(layers "B.Cu" "B.Mask" "B.Paste")
			(net "P1V2_AUX")
		)
		(pad "2" smd circle
			(at -0.40005 0)
			(size 0 0)
			(layers "B.Cu" "B.Mask" "B.Paste")
			(net "P1V2_P1V0_I3C_VDDL2")
		)
	)
)
